# T6G (Grand Teton) — schematic netlist excerpt (pin names and nets, part order shuffled) for the footprints in the layout excerpt that follows; sources: Cadence DE-HDL packaged netlist, KiCad conversion of 04192023_DAF0TMB3IC0_F0TG_MB_C_brd_V02_OCP.brd

C6095  Q_CAP  0.1UF 25V 10% X7R  pkg 0402  page 179 : A = P3V3_AUX_CPU0_USB2_AVDD33 ; B = GND
C468  Q_CAP  1000PF 50V 5% X7R  pkg 0402  page 193 : A = PVDDCR_CPU0_P0_EN_R ; B = GND

(kicad_pcb
	(version 20260206)
	(generator "pcbnew")
	(generator_version "10.0")
	(general
		(thickness 1.6)
		(legacy_teardrops no)
	)
	(paper "A4")
	(title_block
		(title "04192023_DAF0TMB3IC0_F0TG_MB_C_brd_V02_OCP.brd")
		(comment 1 "Grand Teton / footprints 7650-7651 of 8354")
	)
	(layers
		(0 "F.Cu" signal "TOP")
		(4 "In1.Cu" signal "GND")
		(6 "In2.Cu" signal "IN1")
		(8 "In3.Cu" signal "GND1")
		(10 "In4.Cu" signal "IN2")
		(12 "In5.Cu" signal "GND2")
		(14 "In6.Cu" signal "IN3")
		(16 "In7.Cu" signal "GND3")
		(18 "In8.Cu" signal "VCC")
		(20 "In9.Cu" signal "VCC1")
		(22 "In10.Cu" signal "GND4")
		(24 "In11.Cu" signal "IN4")
		(26 "In12.Cu" signal "GND5")
		(28 "In13.Cu" signal "IN5")
		(30 "In14.Cu" signal "GND6")
		(32 "In15.Cu" signal "IN6")
		(34 "In16.Cu" signal "GND7")
		(2 "B.Cu" signal "BOTTOM")
		(9 "F.Adhes" user "F.Adhesive")
		(11 "B.Adhes" user "B.Adhesive")
		(13 "F.Paste" user "Package Geometry/Pastemask Top")
		(15 "B.Paste" user "Package Geometry/Pastemask Bottom")
		(5 "F.SilkS" user "Ref Des/Silkscreen Top")
		(7 "B.SilkS" user "Ref Des/Silkscreen Bottom")
		(1 "F.Mask" user "Board Geometry/Soldermask Top")
		(3 "B.Mask" user "Board Geometry/Soldermask Bottom")
		(17 "Dwgs.User" user "User.Drawings")
		(19 "Cmts.User" user "User.Comments")
		(21 "Eco1.User" user "User.Eco1")
		(23 "Eco2.User" user "User.Eco2")
		(25 "Edge.Cuts" user "Board Geometry/Outline")
		(27 "Margin" user)
		(31 "F.CrtYd" user "Package Geometry/Place Bound Top")
		(29 "B.CrtYd" user "Package Geometry/Place Bound Bottom")
		(35 "F.Fab" user "Ref Des/Assembly Top")
		(33 "B.Fab" user "Ref Des/Assembly Bottom")
	)
	(footprint ""
		(layer "B.Cu")
		(at 372.937278 -140.456158)
		(property "Reference" "C468"
			(at 0 0 0)
			(layer "B.SilkS")
			(hide yes)
			(effects
				(font
					(size 1.27 1.27)
				)
				(justify mirror)
			)
		)
		(property "Value" ""
			(at 0 0 0)
			(layer "B.Fab")
			(effects
				(font
					(size 1.27 1.27)
				)
				(justify mirror)
			)
		)
		(duplicate_pad_numbers_are_jumpers no)
		(fp_line
			(start -0.7874 -0.4064)
			(end -0.7874 0.4064)
			(stroke
				(width 0.1524)
				(type default)
			)
			(layer "B.SilkS")
		)
		(fp_line
			(start -0.7874 0.4064)
			(end 0.7874 0.4064)
			(stroke
				(width 0.1524)
				(type default)
			)
			(layer "B.SilkS")
		)
		(fp_line
			(start 0.7874 -0.4064)
			(end -0.7874 -0.4064)
			(stroke
				(width 0.1524)
				(type default)
			)
			(layer "B.SilkS")
		)
		(fp_line
			(start 0.7874 0.4064)
			(end 0.7874 -0.4064)
			(stroke
				(width 0.1524)
				(type default)
			)
			(layer "B.SilkS")
		)
		(fp_line
			(start -0.67945 -0.3048)
			(end -0.67945 0.3048)
			(stroke
				(width 0.1)
				(type default)
			)
			(layer "B.Fab")
		)
		(fp_line
			(start -0.67945 0.3048)
			(end -0.120396 0.3048)
			(stroke
				(width 0.1)
				(type default)
			)
			(layer "B.Fab")
		)
		(fp_line
			(start -0.12065 -0.3048)
			(end -0.67945 -0.3048)
			(stroke
				(width 0.1)
				(type default)
			)
			(layer "B.Fab")
		)
		(fp_line
			(start -0.12065 -0.2794)
			(end -0.12065 -0.3048)
			(stroke
				(width 0.1)
				(type default)
			)
			(layer "B.Fab")
		)
		(fp_line
			(start -0.120396 0.2794)
			(end 0.12065 0.2794)
			(stroke
				(width 0.1)
				(type default)
			)
			(layer "B.Fab")
		)
		(fp_line
			(start -0.120396 0.3048)
			(end -0.120396 0.2794)
			(stroke
				(width 0.1)
				(type default)
			)
			(layer "B.Fab")
		)
		(fp_line
			(start 0.12065 -0.305054)
			(end 0.12065 -0.2794)
			(stroke
				(width 0.1)
				(type default)
			)
			(layer "B.Fab")
		)
		(fp_line
			(start 0.12065 -0.2794)
			(end -0.12065 -0.2794)
			(stroke
				(width 0.1)
				(type default)
			)
			(layer "B.Fab")
		)
		(fp_line
			(start 0.12065 0.2794)
			(end 0.12065 0.3048)
			(stroke
				(width 0.1)
				(type default)
			)
			(layer "B.Fab")
		)
		(fp_line
			(start 0.12065 0.3048)
			(end 0.67945 0.3048)
			(stroke
				(width 0.1)
				(type default)
			)
			(layer "B.Fab")
		)
		(fp_line
			(start 0.67945 -0.305054)
			(end 0.12065 -0.305054)
			(stroke
				(width 0.1)
				(type default)
			)
			(layer "B.Fab")
		)
		(fp_line
			(start 0.67945 0.3048)
			(end 0.67945 -0.305054)
			(stroke
				(width 0.1)
				(type default)
			)
			(layer "B.Fab")
		)
		(pad "1" smd circle
			(at 0.40005 0 180)
			(size 0 0)
			(layers "B.Cu" "B.Mask" "B.Paste")
			(net "PVDDCR_CPU0_P0_EN_R")
		)
		(pad "2" smd circle
			(at -0.40005 0 180)
			(size 0 0)
			(layers "B.Cu" "B.Mask" "B.Paste")
			(net "GND")
		)
	)
	(footprint ""
		(layer "B.Cu")
		(at 109.550454 -33.603438 180)
		(property "Reference" "C6095"
			(at 0 0 0)
			(layer "B.SilkS")
			(hide yes)
			(effects
				(font
					(size 1.27 1.27)
				)
				(justify mirror)
			)
		)
		(property "Value" ""
			(at 0 0 0)
			(layer "B.Fab")
			(effects
				(font
					(size 1.27 1.27)
				)
				(justify mirror)
			)
		)
		(duplicate_pad_numbers_are_jumpers no)
		(fp_line
			(start 0.7874 0.4064)
			(end 0.7874 -0.4064)
			(stroke
				(width 0.1524)
				(type default)
			)
			(layer "B.SilkS")
		)
		(fp_line
			(start 0.7874 -0.4064)
			(end -0.7874 -0.4064)
			(stroke
				(width 0.1524)
				(type default)
			)
			(layer "B.SilkS")
		)
		(fp_line
			(start -0.7874 0.4064)
			(end 0.7874 0.4064)
			(stroke
				(width 0.1524)
				(type default)
			)
			(layer "B.SilkS")
		)
		(fp_line
			(start -0.7874 -0.4064)
			(end -0.7874 0.4064)
			(stroke
				(width 0.1524)
				(type default)
			)
			(layer "B.SilkS")
		)
		(fp_line
			(start 0.67945 0.3048)
			(end 0.67945 -0.305054)
			(stroke
				(width 0.1)
				(type default)
			)
			(layer "B.Fab")
		)
		(fp_line
			(start 0.67945 -0.305054)
			(end 0.12065 -0.305054)
			(stroke
				(width 0.1)
				(type default)
			)
			(layer "B.Fab")
		)
		(fp_line
			(start 0.12065 0.3048)
			(end 0.67945 0.3048)
			(stroke
				(width 0.1)
				(type default)
			)
			(layer "B.Fab")
		)
		(fp_line
			(start 0.12065 0.2794)
			(end 0.12065 0.3048)
			(stroke
				(width 0.1)
				(type default)
			)
			(layer "B.Fab")
		)
		(fp_line
			(start 0.12065 -0.2794)
			(end -0.12065 -0.2794)
			(stroke
				(width 0.1)
				(type default)
			)
			(layer "B.Fab")
		)
		(fp_line
			(start 0.12065 -0.305054)
			(end 0.12065 -0.2794)
			(stroke
				(width 0.1)
				(type default)
			)
			(layer "B.Fab")
		)
		(fp_line
			(start -0.120396 0.3048)
			(end -0.120396 0.2794)
			(stroke
				(width 0.1)
				(type default)
			)
			(layer "B.Fab")
		)
		(fp_line
			(start -0.120396 0.2794)
			(end 0.12065 0.2794)
			(stroke
				(width 0.1)
				(type default)
			)
			(layer "B.Fab")
		)
		(fp_line
			(start -0.12065 -0.2794)
			(end -0.12065 -0.3048)
			(stroke
				(width 0.1)
				(type default)
			)
			(layer "B.Fab")
		)
		(fp_line
			(start -0.12065 -0.3048)
			(end -0.67945 -0.3048)
			(stroke
				(width 0.1)
				(type default)
			)
			(layer "B.Fab")
		)
		(fp_line
			(start -0.67945 0.3048)
			(end -0.120396 0.3048)
			(stroke
				(width 0.1)
				(type default)
			)
			(layer "B.Fab")
		)
		(fp_line
			(start -0.67945 -0.3048)
			(end -0.67945 0.3048)
			(stroke
				(width 0.1)
				(type default)
			)
			(layer "B.Fab")
		)
		(pad "1" smd circle
			(at 0.40005 0)
			(size 0 0)
			(layers "B.Cu" "B.Mask" "B.Paste")
			(net "P3V3_AUX_CPU0_USB2_AVDD33")
		)
		(pad "2" smd circle
			(at -0.40005 0)
			(size 0 0)
			(layers "B.Cu" "B.Mask" "B.Paste")
			(net "GND")
		)
	)
)
